# BASEBOARD_FAB2 (Tioga Pass) — schematic netlist excerpt (pin names and nets, part order shuffled) for the footprints in the layout excerpt that follows; sources: Cadence DE-HDL packaged netlist, KiCad conversion of Wiwynn_Tioga_Pass_MB.brd

J9B3  SCONN120_A28699018  SCONN  pkg SM  page 186
  IO1  = FM_MEZZA_PRSNT1_N
  IO2  = P12V_STBY
  IO3  = P5V_STBY
  IO4  = P12V_STBY
  IO5  = P5V_STBY
  IO6  = P12V_STBY
  IO7  = P5V_STBY
  IO8  = GND
  IO9  = GND
  IO10  = GND
  IO11  = GND
  IO12  = P3V3_STBY
  IO13  = P3V3_STBY
  IO14  = GND
  IO15  = GND
  IO16  = GND
  IO17  = GND
  IO18  = P3V3
  IO19  = P3V3
  IO20  = P3V3
  IO21  = P3V3
  IO22  = P3V3
  IO23  = P3V3
  IO24  = P3V3
  IO25  = P3V3
  IO26  = GND
  IO27  = RMII_BMC_OCP_CRSDV_R
  IO28  = IRQ_MEZZ_LAN_ALERT_N
  IO29  = CLK_50M_CKMNG_OCP
  IO30  = SMB_OCP_FRU_STBY_LVC3_SCL
  IO31  = RMII_BMC_OCP_TXEN
  IO32  = SMB_OCP_FRU_STBY_LVC3_SDA
  IO33  = RST_PCIE_CPU_DEV0_R_N
  IO34  = FM_PE_OCP_WAKE_N
  IO35  = SMB_OCP_LAN_STBY_LVC3_SCL
  IO36  = RMII_BMC_OCP_RXER_R
  IO37  = SMB_OCP_LAN_STBY_LVC3_SDA
  IO38  = GND
  IO39  = GND
  IO40  = RMII_BMC_OCP_TXD0
  IO41  = GND
  IO42  = RMII_BMC_OCP_TXD1
  IO43  = RMII_BMC_OCP_RXD0_R
  IO44  = GND
  IO45  = RMII_BMC_OCP_RXD1_R
  IO46  = GND
  IO47  = GND
  IO48  = CLK_100M_MEZZ1_DP
  IO49  = GND
  IO50  = CLK_100M_MEZZ1_DN
  IO51  = CLK_100M_MEZZ2_DP
  IO52  = GND
  IO53  = CLK_100M_MEZZ2_DN
  IO54  = GND
  IO55  = GND
  IO56  = P3E_OCP_CPU0_PE3_C_TXP<15>
  IO57  = GND
  IO58  = P3E_OCP_CPU0_PE3_C_TXN<15>
  IO59  = P3E_CPU0_PE3_OCP_RXP<15>
  IO60  = GND
  IO61  = P3E_CPU0_PE3_OCP_RXN<15>
  IO62  = GND
  IO63  = GND
  IO64  = P3E_OCP_CPU0_PE3_C_TXP<14>
  IO65  = GND
  IO66  = P3E_OCP_CPU0_PE3_C_TXN<14>
  IO67  = P3E_CPU0_PE3_OCP_RXP<14>
  IO68  = GND
  IO69  = P3E_CPU0_PE3_OCP_RXN<14>
  IO70  = GND
  IO71  = GND
  IO72  = P3E_OCP_CPU0_PE3_C_TXP<13>
  IO73  = GND
  IO74  = P3E_OCP_CPU0_PE3_C_TXN<13>
  IO75  = P3E_CPU0_PE3_OCP_RXP<13>
  IO76  = GND
  IO77  = P3E_CPU0_PE3_OCP_RXN<13>
  IO78  = GND
  IO79  = GND
  IO80  = P3E_OCP_CPU0_PE3_C_TXP<12>
  IO81  = GND
  IO82  = P3E_OCP_CPU0_PE3_C_TXN<12>
  IO83  = P3E_CPU0_PE3_OCP_RXP<12>
  IO84  = GND
  IO85  = P3E_CPU0_PE3_OCP_RXN<12>
  IO86  = GND
  IO87  = GND
  IO88  = P3E_OCP_CPU0_PE3_C_TXP<11>
  IO89  = GND
  IO90  = P3E_OCP_CPU0_PE3_C_TXN<11>
  IO91  = P3E_CPU0_PE3_OCP_RXP<11>
  IO92  = GND
  IO93  = P3E_CPU0_PE3_OCP_RXN<11>
  IO94  = GND
  IO95  = GND
  IO96  = P3E_OCP_CPU0_PE3_C_TXP<10>
  IO97  = GND
  IO98  = P3E_OCP_CPU0_PE3_C_TXN<10>
  IO99  = P3E_CPU0_PE3_OCP_RXP<10>
  IO100  = GND
  IO101  = P3E_CPU0_PE3_OCP_RXN<10>
  IO102  = GND
  IO103  = GND
  IO104  = P3E_OCP_CPU0_PE3_C_TXP<9>
  IO105  = GND
  IO106  = P3E_OCP_CPU0_PE3_C_TXN<9>
  IO107  = P3E_CPU0_PE3_OCP_RXP<9>
  IO108  = GND
  IO109  = P3E_CPU0_PE3_OCP_RXN<9>
  IO110  = GND
  IO111  = GND
  IO112  = P3E_OCP_CPU0_PE3_C_TXP<8>
  IO113  = GND
  IO114  = P3E_OCP_CPU0_PE3_C_TXN<8>
  IO115  = P3E_CPU0_PE3_OCP_RXP<8>
  IO116  = GND
  IO117  = P3E_CPU0_PE3_OCP_RXN<8>
  IO118  = GND
  IO119  = GND
  IO120  = FM_OCP_MEZZA_PRES_N

(kicad_pcb
	(version 20260206)
	(generator "pcbnew")
	(generator_version "10.0")
	(general
		(thickness 1.6)
		(legacy_teardrops no)
	)
	(paper "A4")
	(title_block
		(title "Wiwynn_Tioga_Pass_MB.brd")
		(comment 1 "Tioga Pass / footprint 368 of 4770 (J9B3), pads 50-97 of 122")
	)
	(layers
		(0 "F.Cu" signal "TOP")
		(4 "In1.Cu" signal "L2GND")
		(6 "In2.Cu" signal "L3")
		(8 "In3.Cu" signal "L4GND")
		(10 "In4.Cu" signal "L5")
		(12 "In5.Cu" signal "L6GND")
		(14 "In6.Cu" signal "L7VCC")
		(16 "In7.Cu" signal "L8VCC")
		(18 "In8.Cu" signal "L9GND")
		(20 "In9.Cu" signal "L10")
		(22 "In10.Cu" signal "L11GND")
		(24 "In11.Cu" signal "L12")
		(26 "In12.Cu" signal "L13GND")
		(2 "B.Cu" signal "BOTTOM")
		(9 "F.Adhes" user "F.Adhesive")
		(11 "B.Adhes" user "B.Adhesive")
		(13 "F.Paste" user "Package Geometry/Pastemask Top")
		(15 "B.Paste" user "Package Geometry/Pastemask Bottom")
		(5 "F.SilkS" user "Ref Des/Silkscreen Top")
		(7 "B.SilkS" user "Ref Des/Silkscreen Bottom")
		(1 "F.Mask" user "Board Geometry/Soldermask Top")
		(3 "B.Mask" user "Board Geometry/Soldermask Bottom")
		(17 "Dwgs.User" user "User.Drawings")
		(19 "Cmts.User" user "User.Comments")
		(21 "Eco1.User" user "User.Eco1")
		(23 "Eco2.User" user "User.Eco2")
		(25 "Edge.Cuts" user "Board Geometry/Outline")
		(27 "Margin" user)
		(31 "F.CrtYd" user "Package Geometry/Place Bound Top")
		(29 "B.CrtYd" user "Package Geometry/Place Bound Bottom")
		(35 "F.Fab" user "Ref Des/Assembly Top")
		(33 "B.Fab" user "Ref Des/Assembly Bottom")
	)
	(footprint ""
		(layer "F.Cu")
		(at 487.800904 -116.993162 -90)
		(property "Reference" "J9B3"
			(at -2.227072 26.281888 0)
			(unlocked yes)
			(layer "F.SilkS")
			(effects
				(font
					(size 0.7874 0.5842)
					(thickness 0.1524)
				)
			)
		)
		(property "Value" ""
			(at 0 0 270)
			(layer "F.Fab")
			(effects
				(font
					(size 1.27 1.27)
				)
			)
		)
		(duplicate_pad_numbers_are_jumpers no)
		(pad "48" smd rect
			(at 4.787646 18.400014 270)
			(size 2.3876 0.508)
			(layers "F.Cu" "F.Mask" "F.Paste")
			(net "CLK_100M_MEZZ1_DP")
		)
		(pad "49" smd rect
			(at 0 19.200114 270)
			(size 2.3876 0.508)
			(layers "F.Cu" "F.Mask" "F.Paste")
			(net "GND")
		)
		(pad "50" smd rect
			(at 4.787646 19.200114 270)
			(size 2.3876 0.508)
			(layers "F.Cu" "F.Mask" "F.Paste")
			(net "CLK_100M_MEZZ1_DN")
		)
		(pad "51" smd rect
			(at 0 19.99996 270)
			(size 2.3876 0.508)
			(layers "F.Cu" "F.Mask" "F.Paste")
			(net "CLK_100M_MEZZ2_DP")
		)
		(pad "52" smd rect
			(at 4.787646 19.99996 270)
			(size 2.3876 0.508)
			(layers "F.Cu" "F.Mask" "F.Paste")
			(net "GND")
		)
		(pad "53" smd rect
			(at 0 20.80006 270)
			(size 2.3876 0.508)
			(layers "F.Cu" "F.Mask" "F.Paste")
			(net "CLK_100M_MEZZ2_DN")
		)
		(pad "54" smd rect
			(at 4.787646 20.80006 270)
			(size 2.3876 0.508)
			(layers "F.Cu" "F.Mask" "F.Paste")
			(net "GND")
		)
		(pad "55" smd rect
			(at 0 21.599906 270)
			(size 2.3876 0.508)
			(layers "F.Cu" "F.Mask" "F.Paste")
			(net "GND")
		)
		(pad "56" smd rect
			(at 4.787646 21.599906 270)
			(size 2.3876 0.508)
			(layers "F.Cu" "F.Mask" "F.Paste")
			(net "P3E_OCP_CPU0_PE3_C_TXP<15>")
		)
		(pad "57" smd rect
			(at 0 22.400006 270)
			(size 2.3876 0.508)
			(layers "F.Cu" "F.Mask" "F.Paste")
			(net "GND")
		)
		(pad "58" smd rect
			(at 4.787646 22.400006 270)
			(size 2.3876 0.508)
			(layers "F.Cu" "F.Mask" "F.Paste")
			(net "P3E_OCP_CPU0_PE3_C_TXN<15>")
		)
		(pad "59" smd rect
			(at 0 23.200106 270)
			(size 2.3876 0.508)
			(layers "F.Cu" "F.Mask" "F.Paste")
			(net "P3E_CPU0_PE3_OCP_RXP<15>")
		)
		(pad "60" smd rect
			(at 4.787646 23.200106 270)
			(size 2.3876 0.508)
			(layers "F.Cu" "F.Mask" "F.Paste")
			(net "GND")
		)
		(pad "61" smd rect
			(at 0 23.999952 270)
			(size 2.3876 0.508)
			(layers "F.Cu" "F.Mask" "F.Paste")
			(net "P3E_CPU0_PE3_OCP_RXN<15>")
		)
		(pad "62" smd rect
			(at 4.787646 23.999952 270)
			(size 2.3876 0.508)
			(layers "F.Cu" "F.Mask" "F.Paste")
			(net "GND")
		)
		(pad "63" smd rect
			(at 0 24.800052 270)
			(size 2.3876 0.508)
			(layers "F.Cu" "F.Mask" "F.Paste")
			(net "GND")
		)
		(pad "64" smd rect
			(at 4.787646 24.800052 270)
			(size 2.3876 0.508)
			(layers "F.Cu" "F.Mask" "F.Paste")
			(net "P3E_OCP_CPU0_PE3_C_TXP<14>")
		)
		(pad "65" smd rect
			(at 0 25.599898 270)
			(size 2.3876 0.508)
			(layers "F.Cu" "F.Mask" "F.Paste")
			(net "GND")
		)
		(pad "66" smd rect
			(at 4.787646 25.599898 270)
			(size 2.3876 0.508)
			(layers "F.Cu" "F.Mask" "F.Paste")
			(net "P3E_OCP_CPU0_PE3_C_TXN<14>")
		)
		(pad "67" smd rect
			(at 0 26.399998 270)
			(size 2.3876 0.508)
			(layers "F.Cu" "F.Mask" "F.Paste")
			(net "P3E_CPU0_PE3_OCP_RXP<14>")
		)
		(pad "68" smd rect
			(at 4.787646 26.399998 270)
			(size 2.3876 0.508)
			(layers "F.Cu" "F.Mask" "F.Paste")
			(net "GND")
		)
		(pad "69" smd rect
			(at 0 27.200098 270)
			(size 2.3876 0.508)
			(layers "F.Cu" "F.Mask" "F.Paste")
			(net "P3E_CPU0_PE3_OCP_RXN<14>")
		)
		(pad "70" smd rect
			(at 4.787646 27.200098 270)
			(size 2.3876 0.508)
			(layers "F.Cu" "F.Mask" "F.Paste")
			(net "GND")
		)
		(pad "71" smd rect
			(at 0 27.999944 270)
			(size 2.3876 0.508)
			(layers "F.Cu" "F.Mask" "F.Paste")
			(net "GND")
		)
		(pad "72" smd rect
			(at 4.787646 27.999944 270)
			(size 2.3876 0.508)
			(layers "F.Cu" "F.Mask" "F.Paste")
			(net "P3E_OCP_CPU0_PE3_C_TXP<13>")
		)
		(pad "73" smd rect
			(at 0 28.800044 270)
			(size 2.3876 0.508)
			(layers "F.Cu" "F.Mask" "F.Paste")
			(net "GND")
		)
		(pad "74" smd rect
			(at 4.787646 28.800044 270)
			(size 2.3876 0.508)
			(layers "F.Cu" "F.Mask" "F.Paste")
			(net "P3E_OCP_CPU0_PE3_C_TXN<13>")
		)
		(pad "75" smd rect
			(at 0 29.59989 270)
			(size 2.3876 0.508)
			(layers "F.Cu" "F.Mask" "F.Paste")
			(net "P3E_CPU0_PE3_OCP_RXP<13>")
		)
		(pad "76" smd rect
			(at 4.787646 29.59989 270)
			(size 2.3876 0.508)
			(layers "F.Cu" "F.Mask" "F.Paste")
			(net "GND")
		)
		(pad "77" smd rect
			(at 0 30.39999 270)
			(size 2.3876 0.508)
			(layers "F.Cu" "F.Mask" "F.Paste")
			(net "P3E_CPU0_PE3_OCP_RXN<13>")
		)
		(pad "78" smd rect
			(at 4.787646 30.39999 270)
			(size 2.3876 0.508)
			(layers "F.Cu" "F.Mask" "F.Paste")
			(net "GND")
		)
		(pad "79" smd rect
			(at 0 31.20009 270)
			(size 2.3876 0.508)
			(layers "F.Cu" "F.Mask" "F.Paste")
			(net "GND")
		)
		(pad "80" smd rect
			(at 4.787646 31.20009 270)
			(size 2.3876 0.508)
			(layers "F.Cu" "F.Mask" "F.Paste")
			(net "P3E_OCP_CPU0_PE3_C_TXP<12>")
		)
		(pad "81" smd rect
			(at 0 31.999936 270)
			(size 2.3876 0.508)
			(layers "F.Cu" "F.Mask" "F.Paste")
			(net "GND")
		)
		(pad "82" smd rect
			(at 4.787646 31.999936 270)
			(size 2.3876 0.508)
			(layers "F.Cu" "F.Mask" "F.Paste")
			(net "P3E_OCP_CPU0_PE3_C_TXN<12>")
		)
		(pad "83" smd rect
			(at 0 32.800036 270)
			(size 2.3876 0.508)
			(layers "F.Cu" "F.Mask" "F.Paste")
			(net "P3E_CPU0_PE3_OCP_RXP<12>")
		)
		(pad "84" smd rect
			(at 4.787646 32.800036 270)
			(size 2.3876 0.508)
			(layers "F.Cu" "F.Mask" "F.Paste")
			(net "GND")
		)
		(pad "85" smd rect
			(at 0 33.599882 270)
			(size 2.3876 0.508)
			(layers "F.Cu" "F.Mask" "F.Paste")
			(net "P3E_CPU0_PE3_OCP_RXN<12>")
		)
		(pad "86" smd rect
			(at 4.787646 33.599882 270)
			(size 2.3876 0.508)
			(layers "F.Cu" "F.Mask" "F.Paste")
			(net "GND")
		)
		(pad "87" smd rect
			(at 0 34.399982 270)
			(size 2.3876 0.508)
			(layers "F.Cu" "F.Mask" "F.Paste")
			(net "GND")
		)
		(pad "88" smd rect
			(at 4.787646 34.399982 270)
			(size 2.3876 0.508)
			(layers "F.Cu" "F.Mask" "F.Paste")
			(net "P3E_OCP_CPU0_PE3_C_TXP<11>")
		)
		(pad "89" smd rect
			(at 0 35.200082 270)
			(size 2.3876 0.508)
			(layers "F.Cu" "F.Mask" "F.Paste")
			(net "GND")
		)
		(pad "90" smd rect
			(at 4.787646 35.200082 270)
			(size 2.3876 0.508)
			(layers "F.Cu" "F.Mask" "F.Paste")
			(net "P3E_OCP_CPU0_PE3_C_TXN<11>")
		)
		(pad "91" smd rect
			(at 0 35.999928 270)
			(size 2.3876 0.508)
			(layers "F.Cu" "F.Mask" "F.Paste")
			(net "P3E_CPU0_PE3_OCP_RXP<11>")
		)
		(pad "92" smd rect
			(at 4.787646 35.999928 270)
			(size 2.3876 0.508)
			(layers "F.Cu" "F.Mask" "F.Paste")
			(net "GND")
		)
		(pad "93" smd rect
			(at 0 36.800028 270)
			(size 2.3876 0.508)
			(layers "F.Cu" "F.Mask" "F.Paste")
			(net "P3E_CPU0_PE3_OCP_RXN<11>")
		)
		(pad "94" smd rect
			(at 4.787646 36.800028 270)
			(size 2.3876 0.508)
			(layers "F.Cu" "F.Mask" "F.Paste")
			(net "GND")
		)
		(pad "95" smd rect
			(at 0 37.599874 270)
			(size 2.3876 0.508)
			(layers "F.Cu" "F.Mask" "F.Paste")
			(net "GND")
		)
	)
)
